FILE_TYPE = MACRO_DRAWING;
SET COLOR_WIRE YELLOW;
SET COLOR_PROP ORANGE;
SET COLOR_DOT WHITE;
SET COLOR_ARC YELLOW;
SET COLOR_BODY GREEN;
SET COLOR_NOTE PURPLE;
SET PROP_DISPLAY VALUE;
SET PAGE_NUMBER P22;
FORCEADD SHEET_A1..1
(-250 750);
FORCEPROP 2 LAST CUSTOM_TXT_CDS <XR_PAGE_TITLE>
J 0
(-15820 12100);
DISPLAY 0.638298 (-15820 12100);
PAINT PINK (-15820 12100);
FORCEPROP 1 LAST CUSTOM_TXT_CDS <DOCNO>
J 0
(-2300 1135);
DISPLAY 0.978723 (-2300 1135);
FORCEPROP 1 LAST CUSTOM_TXT_CDS <CON_PAGE_NUM>
J 0
(-2405 800);
DISPLAY 0.978723 (-2405 800);
FORCEPROP 1 LAST CUSTOM_TXT_CDS <DATE>
J 0
(-950 925);
DISPLAY 0.978723 (-950 925);
FORCEPROP 1 LAST CUSTOM_TXT_CDS <TITLE>
J 1
(-2035 1380);
DISPLAY 0.978723 (-2035 1380);
FORCEPROP 1 LAST CUSTOM_TXT_CDS <DESIGNER>
J 0
(-950 1350);
DISPLAY 0.978723 (-950 1350);
FORCEPROP 1 LAST CUSTOM_TXT_CDS <CON_TOTAL_PAGES>
J 0
(-2095 800);
DISPLAY 0.808511 (-2095 800);
FORCEPROP 1 LAST CUSTOM_TXT_CDS <ASSY_PN>
J 0
(-2300 925);
DISPLAY 0.978723 (-2300 925);
FORCEPROP 1 LAST CUSTOM_TXT_CDS <DOCREV>
J 0
(-950 1125);
DISPLAY 0.978723 (-950 1125);
FORCEPROP 1 LAST TITLE PWR_SEQ_DIAGRAM
J 0
(-2750 1650);
DISPLAY 3.085106 (-2750 1650);
FORCEPROP 2 LAST CDS_LIB cls
J 0
(-250 750);
DISPLAY INVISIBLE (-250 750);
FORCEPROP 1 LAST CDS_LMAN_SYM_OUTLINE -15850,11500,200,-200
J 0
(-250 750);
DISPLAY 0.468085 (-250 750);
PAINT GREEN (-250 750);
DISPLAY INVISIBLE (-250 750);
FORCEPROP 2 LAST PAGE_BORDER TRUE
J 0
(-15820 12100);
DISPLAY 0.638298 (-15820 12100);
PAINT PINK (-15820 12100);
DISPLAY INVISIBLE (-15820 12100);
FORCEPROP 2 LAST CDS_XR_PAGE_TITLE CR-5 : @TIMECARD_LIB.TIMECARD(SCH_1):PAGE5
J 0
(-15820 12100);
DISPLAY 0.638298 (-15820 12100);
PAINT PINK (-15820 12100);
DISPLAY INVISIBLE (-15820 12100);
FORCEPROP 1 LAST COMMENT_BODY TRUE
J 0
(-240 805);
DISPLAY 0.808511 (-240 805);
DISPLAY INVISIBLE (-240 805);
FORCENOTE
PWR_SEQ_DIAGRAM
(-9850 10550) 0;
DISPLAY LEFT (-9850 10550);
DISPLAY 4.914894 (-9850 10550);
FORCENOTE
$CDS_IMAGE|clipboard_1.jpg|7118|3590
(-8200 7650) 0;
DISPLAY LEFT (-8200 7650);
QUIT
